(kicad_pcb
	(version 20260206)
	(generator "pcbnew")
	(generator_version "10.0")
	(general
		(thickness 1.6)
		(legacy_teardrops no)
	)
	(paper "A4")
	(title_block
		(title "Wiwynn_Tioga_Pass_MB.brd")
		(comment 1 "Tioga Pass / footprints 3063-3070 of 4770")
	)
	(layers
		(0 "F.Cu" signal "TOP")
		(4 "In1.Cu" signal "L2GND")
		(6 "In2.Cu" signal "L3")
		(8 "In3.Cu" signal "L4GND")
		(10 "In4.Cu" signal "L5")
		(12 "In5.Cu" signal "L6GND")
		(14 "In6.Cu" signal "L7VCC")
		(16 "In7.Cu" signal "L8VCC")
		(18 "In8.Cu" signal "L9GND")
		(20 "In9.Cu" signal "L10")
		(22 "In10.Cu" signal "L11GND")
		(24 "In11.Cu" signal "L12")
		(26 "In12.Cu" signal "L13GND")
		(2 "B.Cu" signal "BOTTOM")
		(9 "F.Adhes" user "F.Adhesive")
		(11 "B.Adhes" user "B.Adhesive")
		(13 "F.Paste" user "Package Geometry/Pastemask Top")
		(15 "B.Paste" user "Package Geometry/Pastemask Bottom")
		(5 "F.SilkS" user "Ref Des/Silkscreen Top")
		(7 "B.SilkS" user "Ref Des/Silkscreen Bottom")
		(1 "F.Mask" user "Board Geometry/Soldermask Top")
		(3 "B.Mask" user "Board Geometry/Soldermask Bottom")
		(17 "Dwgs.User" user "User.Drawings")
		(19 "Cmts.User" user "User.Comments")
		(21 "Eco1.User" user "User.Eco1")
		(23 "Eco2.User" user "User.Eco2")
		(25 "Edge.Cuts" user "Board Geometry/Outline")
		(27 "Margin" user)
		(31 "F.CrtYd" user "Package Geometry/Place Bound Top")
		(29 "B.CrtYd" user "Package Geometry/Place Bound Bottom")
		(35 "F.Fab" user "Ref Des/Assembly Top")
		(33 "B.Fab" user "Ref Des/Assembly Bottom")
	)
	(footprint ""
		(layer "B.Cu")
		(at 333.6798 -30.3403 90)
		(property "Reference" "C3T7"
			(at 0 0 90)
			(layer "B.SilkS")
			(hide yes)
			(effects
				(font
					(size 1.27 1.27)
				)
				(justify mirror)
			)
		)
		(property "Value" ""
			(at 0 0 90)
			(layer "B.Fab")
			(effects
				(font
					(size 1.27 1.27)
				)
				(justify mirror)
			)
		)
		(duplicate_pad_numbers_are_jumpers no)
		(fp_rect
			(start -0.7239 -0.2159)
			(end 0.7239 1.9939)
			(stroke
				(width 0)
				(type default)
			)
			(fill no)
			(layer "B.CrtYd")
		)
		(fp_line
			(start 0.7239 -0.2159)
			(end 0.7239 1.9939)
			(stroke
				(width 0.1)
				(type default)
			)
			(layer "B.Fab")
		)
		(fp_line
			(start -0.7239 -0.2159)
			(end 0.7239 -0.2159)
			(stroke
				(width 0.1)
				(type default)
			)
			(layer "B.Fab")
		)
		(fp_line
			(start 0.7239 1.9939)
			(end -0.7239 1.9939)
			(stroke
				(width 0.1)
				(type default)
			)
			(layer "B.Fab")
		)
		(fp_line
			(start -0.7239 1.9939)
			(end -0.7239 -0.2159)
			(stroke
				(width 0.1)
				(type default)
			)
			(layer "B.Fab")
		)
		(pad "1" smd rect
			(at 0 0 270)
			(size 1.27 1.016)
			(layers "B.Cu" "B.Mask" "B.Paste")
			(net "PVPP_ABC")
		)
		(pad "2" smd rect
			(at 0 1.778 270)
			(size 1.27 1.016)
			(layers "B.Cu" "B.Mask" "B.Paste")
			(net "GND")
		)
		(zone
			(layer "B.Cu")
			(hatch none 0.5)
			(connect_pads
				(clearance 0)
			)
			(min_thickness 0.25)
			(keepout
				(tracks not_allowed)
				(vias allowed)
				(pads allowed)
				(copperpour not_allowed)
				(footprints allowed)
			)
			(placement
				(enabled no)
				(sheetname "")
			)
			(fill
				(thermal_gap 0.5)
				(thermal_bridge_width 0.5)
				(island_removal_mode 0)
			)
			(polygon
				(pts
					(xy 334.1878 -29.7053) (xy 334.9498 -29.7053) (xy 334.9498 -30.9753) (xy 334.1878 -30.9753)
				)
			)
		)
	)
	(footprint ""
		(layer "B.Cu")
		(at 348.1832 -96.5708 -90)
		(property "Reference" "C3N33"
			(at 0 0 90)
			(layer "B.SilkS")
			(hide yes)
			(effects
				(font
					(size 1.27 1.27)
				)
				(justify mirror)
			)
		)
		(property "Value" ""
			(at 0 0 90)
			(layer "B.Fab")
			(effects
				(font
					(size 1.27 1.27)
				)
				(justify mirror)
			)
		)
		(duplicate_pad_numbers_are_jumpers no)
		(fp_poly
			(pts
				(xy 0.7239 -0.2159) (xy -0.7239 -0.2159) (xy -0.7239 1.9939) (xy 0.7239 1.9939)
			)
			(stroke
				(width 0)
				(type default)
			)
			(fill no)
			(layer "B.CrtYd")
		)
		(fp_line
			(start -0.7239 1.9939)
			(end -0.7239 -0.2159)
			(stroke
				(width 0.1)
				(type default)
			)
			(layer "B.Fab")
		)
		(fp_line
			(start 0.7239 1.9939)
			(end -0.7239 1.9939)
			(stroke
				(width 0.1)
				(type default)
			)
			(layer "B.Fab")
		)
		(fp_line
			(start -0.7239 -0.2159)
			(end 0.7239 -0.2159)
			(stroke
				(width 0.1)
				(type default)
			)
			(layer "B.Fab")
		)
		(fp_line
			(start 0.7239 -0.2159)
			(end 0.7239 1.9939)
			(stroke
				(width 0.1)
				(type default)
			)
			(layer "B.Fab")
		)
		(pad "1" smd rect
			(at 0 0 90)
			(size 1.27 1.016)
			(layers "B.Cu" "B.Mask" "B.Paste")
			(net "VR_FET_SW_P12V_STBY_PVCCIO_CPU0")
		)
		(pad "2" smd rect
			(at 0 1.778 90)
			(size 1.27 1.016)
			(layers "B.Cu" "B.Mask" "B.Paste")
			(net "GND")
		)
		(zone
			(layer "B.Cu")
			(hatch none 0.5)
			(connect_pads
				(clearance 0)
			)
			(min_thickness 0.25)
			(keepout
				(tracks not_allowed)
				(vias allowed)
				(pads allowed)
				(copperpour not_allowed)
				(footprints allowed)
			)
			(placement
				(enabled no)
				(sheetname "")
			)
			(fill
				(thermal_gap 0.5)
				(thermal_bridge_width 0.5)
				(island_removal_mode 0)
			)
			(polygon
				(pts
					(xy 347.6752 -95.9358) (xy 347.6752 -97.2058) (xy 346.9132 -97.2058) (xy 346.9132 -95.9358)
				)
			)
		)
	)
	(footprint ""
		(layer "B.Cu")
		(at 404.204424 -32.801052)
		(property "Reference" "C25W34"
			(at 0.8382 -0.67818 0)
			(unlocked yes)
			(layer "B.SilkS")
			(effects
				(font
					(size 0.4064 0.254)
					(thickness 0.1524)
				)
				(justify left mirror)
			)
		)
		(property "Value" ""
			(at 0 0 0)
			(layer "B.Fab")
			(effects
				(font
					(size 1.27 1.27)
				)
				(justify mirror)
			)
		)
		(duplicate_pad_numbers_are_jumpers no)
		(fp_poly
			(pts
				(xy -0.3048 -0.1016) (xy -0.3048 0.9906) (xy 0.3048 0.9906) (xy 0.3048 -0.1016)
			)
			(stroke
				(width 0)
				(type default)
			)
			(fill no)
			(layer "B.CrtYd")
		)
		(fp_line
			(start -0.3048 -0.1016)
			(end 0.3048 -0.1016)
			(stroke
				(width 0.1)
				(type default)
			)
			(layer "B.Fab")
		)
		(fp_line
			(start -0.3048 0.9906)
			(end -0.3048 -0.1016)
			(stroke
				(width 0.1)
				(type default)
			)
			(layer "B.Fab")
		)
		(fp_line
			(start 0.3048 -0.1016)
			(end 0.3048 0.9906)
			(stroke
				(width 0.1)
				(type default)
			)
			(layer "B.Fab")
		)
		(fp_line
			(start 0.3048 0.9906)
			(end -0.3048 0.9906)
			(stroke
				(width 0.1)
				(type default)
			)
			(layer "B.Fab")
		)
		(pad "1" smd rect
			(at 0 0 180)
			(size 0.508 0.508)
			(layers "B.Cu" "B.Mask" "B.Paste")
			(net "VCC_DACAV3V3")
		)
		(pad "2" smd rect
			(at 0 0.889 180)
			(size 0.508 0.508)
			(layers "B.Cu" "B.Mask" "B.Paste")
			(net "GND")
		)
		(zone
			(layer "B.Cu")
			(hatch none 0.5)
			(connect_pads
				(clearance 0)
			)
			(min_thickness 0.25)
			(keepout
				(tracks allowed)
				(vias not_allowed)
				(pads allowed)
				(copperpour not_allowed)
				(footprints allowed)
			)
			(placement
				(enabled no)
				(sheetname "")
			)
			(fill
				(thermal_gap 0.5)
				(thermal_bridge_width 0.5)
				(island_removal_mode 0)
			)
			(polygon
				(pts
					(xy 404.458424 -32.547052) (xy 403.950424 -32.547052) (xy 403.950424 -32.166052) (xy 404.458424 -32.166052)
				)
			)
		)
		(zone
			(layer "B.Cu")
			(hatch none 0.5)
			(connect_pads
				(clearance 0)
			)
			(min_thickness 0.25)
			(keepout
				(tracks not_allowed)
				(vias allowed)
				(pads allowed)
				(copperpour not_allowed)
				(footprints allowed)
			)
			(placement
				(enabled no)
				(sheetname "")
			)
			(fill
				(thermal_gap 0.5)
				(thermal_bridge_width 0.5)
				(island_removal_mode 0)
			)
			(polygon
				(pts
					(xy 404.458424 -32.166052) (xy 403.950424 -32.166052) (xy 403.950424 -32.547052) (xy 404.458424 -32.547052)
				)
			)
		)
	)
	(footprint ""
		(layer "B.Cu")
		(at 425.5008 -14.1732 -90)
		(property "Reference" "R9G29"
			(at 0 0 90)
			(layer "B.SilkS")
			(hide yes)
			(effects
				(font
					(size 1.27 1.27)
				)
				(justify mirror)
			)
		)
		(property "Value" ""
			(at 0 0 90)
			(layer "B.Fab")
			(effects
				(font
					(size 1.27 1.27)
				)
				(justify mirror)
			)
		)
		(duplicate_pad_numbers_are_jumpers no)
		(fp_poly
			(pts
				(xy 0.2794 -0.101854) (xy -0.279654 -0.101854) (xy -0.2794 0.990346) (xy 0.279146 0.990346)
			)
			(stroke
				(width 0)
				(type default)
			)
			(fill no)
			(layer "B.CrtYd")
		)
		(fp_line
			(start -0.2794 0.990346)
			(end -0.279654 -0.101854)
			(stroke
				(width 0.1)
				(type default)
			)
			(layer "B.Fab")
		)
		(fp_line
			(start 0.279146 0.990346)
			(end -0.2794 0.990346)
			(stroke
				(width 0.1)
				(type default)
			)
			(layer "B.Fab")
		)
		(fp_line
			(start -0.279654 -0.101854)
			(end 0.2794 -0.101854)
			(stroke
				(width 0.1)
				(type default)
			)
			(layer "B.Fab")
		)
		(fp_line
			(start 0.2794 -0.101854)
			(end 0.279146 0.990346)
			(stroke
				(width 0.1)
				(type default)
			)
			(layer "B.Fab")
		)
		(pad "1" smd rect
			(at 0 0 90)
			(size 0.508 0.508)
			(layers "B.Cu" "B.Mask" "B.Paste")
			(net "H_CPU0_MEMDEF_MEMHOT_LVT3_N")
		)
		(pad "2" smd rect
			(at 0 0.889 90)
			(size 0.508 0.508)
			(layers "B.Cu" "B.Mask" "B.Paste")
			(net "H_CPU0_MEMDEF_MEMHOT_LVT3_BMC_N")
		)
		(zone
			(layer "B.Cu")
			(hatch none 0.5)
			(connect_pads
				(clearance 0)
			)
			(min_thickness 0.25)
			(keepout
				(tracks not_allowed)
				(vias allowed)
				(pads allowed)
				(copperpour not_allowed)
				(footprints allowed)
			)
			(placement
				(enabled no)
				(sheetname "")
			)
			(fill
				(thermal_gap 0.5)
				(thermal_bridge_width 0.5)
				(island_removal_mode 0)
			)
			(polygon
				(pts
					(xy 424.866054 -13.9192) (xy 424.866054 -14.427454) (xy 425.247054 -14.4272) (xy 425.247054 -13.9192)
				)
			)
		)
		(zone
			(layer "B.Cu")
			(hatch none 0.5)
			(connect_pads
				(clearance 0)
			)
			(min_thickness 0.25)
			(keepout
				(tracks allowed)
				(vias not_allowed)
				(pads allowed)
				(copperpour not_allowed)
				(footprints allowed)
			)
			(placement
				(enabled no)
				(sheetname "")
			)
			(fill
				(thermal_gap 0.5)
				(thermal_bridge_width 0.5)
				(island_removal_mode 0)
			)
			(polygon
				(pts
					(xy 425.247054 -13.9192) (xy 425.247054 -14.4272) (xy 424.866054 -14.427454) (xy 424.866054 -13.9192)
				)
			)
		)
	)
	(footprint ""
		(layer "B.Cu")
		(at 480.2251 -45.3644 90)
		(property "Reference" "C1R17"
			(at 0 0 90)
			(layer "B.SilkS")
			(hide yes)
			(effects
				(font
					(size 1.27 1.27)
				)
				(justify mirror)
			)
		)
		(property "Value" ""
			(at 0 0 90)
			(layer "B.Fab")
			(effects
				(font
					(size 1.27 1.27)
				)
				(justify mirror)
			)
		)
		(duplicate_pad_numbers_are_jumpers no)
		(fp_poly
			(pts
				(xy 0.4953 -0.2032) (xy -0.4953 -0.2032) (xy -0.4953 1.6002) (xy 0.4953 1.6002)
			)
			(stroke
				(width 0)
				(type default)
			)
			(fill no)
			(layer "B.CrtYd")
		)
		(fp_line
			(start 0.4953 -0.2032)
			(end -0.4953 -0.2032)
			(stroke
				(width 0.1)
				(type default)
			)
			(layer "B.Fab")
		)
		(fp_line
			(start -0.4953 -0.2032)
			(end -0.4953 1.6002)
			(stroke
				(width 0.1)
				(type default)
			)
			(layer "B.Fab")
		)
		(fp_line
			(start 0.4953 1.6002)
			(end 0.4953 -0.2032)
			(stroke
				(width 0.1)
				(type default)
			)
			(layer "B.Fab")
		)
		(fp_line
			(start -0.4953 1.6002)
			(end 0.4953 1.6002)
			(stroke
				(width 0.1)
				(type default)
			)
			(layer "B.Fab")
		)
		(pad "1" smd rect
			(at 0 0 270)
			(size 0.762 0.889)
			(layers "B.Cu" "B.Mask" "B.Paste")
			(net "P1V5_LAN")
		)
		(pad "2" smd rect
			(at 0 1.397 270)
			(size 0.762 0.889)
			(layers "B.Cu" "B.Mask" "B.Paste")
			(net "GND")
		)
		(zone
			(layer "B.Cu")
			(hatch none 0.5)
			(connect_pads
				(clearance 0)
			)
			(min_thickness 0.25)
			(keepout
				(tracks not_allowed)
				(vias allowed)
				(pads allowed)
				(copperpour not_allowed)
				(footprints allowed)
			)
			(placement
				(enabled no)
				(sheetname "")
			)
			(fill
				(thermal_gap 0.5)
				(thermal_bridge_width 0.5)
				(island_removal_mode 0)
			)
			(polygon
				(pts
					(xy 480.6696 -45.7454) (xy 480.6696 -44.9834) (xy 481.1776 -44.9834) (xy 481.1776 -45.7454)
				)
			)
		)
	)
	(footprint ""
		(layer "B.Cu")
		(at 107.8611 -145.0086 90)
		(property "Reference" "C7L5"
			(at -1.848866 0.752348 90)
			(unlocked yes)
			(layer "B.SilkS")
			(effects
				(font
					(size 1.27 0.9652)
					(thickness 0.1524)
				)
				(justify mirror)
			)
		)
		(property "Value" ""
			(at 0 0 90)
			(layer "B.Fab")
			(effects
				(font
					(size 1.27 1.27)
				)
				(justify mirror)
			)
		)
		(duplicate_pad_numbers_are_jumpers no)
		(fp_rect
			(start 0.500126 1.598422)
			(end -0.500126 -0.201422)
			(stroke
				(width 0)
				(type default)
			)
			(fill no)
			(layer "B.CrtYd")
		)
		(fp_line
			(start 0.500126 -0.201422)
			(end -0.500126 -0.201422)
			(stroke
				(width 0.1)
				(type default)
			)
			(layer "B.Fab")
		)
		(fp_line
			(start -0.500126 -0.201422)
			(end -0.500126 1.598422)
			(stroke
				(width 0.1)
				(type default)
			)
			(layer "B.Fab")
		)
		(fp_line
			(start 0.500126 1.598422)
			(end 0.500126 -0.201422)
			(stroke
				(width 0.1)
				(type default)
			)
			(layer "B.Fab")
		)
		(fp_line
			(start -0.500126 1.598422)
			(end 0.500126 1.598422)
			(stroke
				(width 0.1)
				(type default)
			)
			(layer "B.Fab")
		)
		(pad "1" smd rect
			(at 0 0)
			(size 0.889 0.9906)
			(layers "B.Cu" "B.Mask" "B.Paste")
			(net "PVDDQ_KLM")
		)
		(pad "2" smd rect
			(at 0 1.397)
			(size 0.889 0.9906)
			(layers "B.Cu" "B.Mask" "B.Paste")
			(net "GND")
		)
		(zone
			(layer "B.Cu")
			(hatch none 0.5)
			(connect_pads
				(clearance 0)
			)
			(min_thickness 0.25)
			(keepout
				(tracks not_allowed)
				(vias allowed)
				(pads allowed)
				(copperpour not_allowed)
				(footprints allowed)
			)
			(placement
				(enabled no)
				(sheetname "")
			)
			(fill
				(thermal_gap 0.5)
				(thermal_bridge_width 0.5)
				(island_removal_mode 0)
			)
			(polygon
				(pts
					(xy 108.8136 -145.5039) (xy 108.3056 -145.5039) (xy 108.3056 -144.5133) (xy 108.8136 -144.5133)
				)
			)
		)
		(zone
			(layer "B.Cu")
			(hatch none 0.5)
			(connect_pads
				(clearance 0)
			)
			(min_thickness 0.25)
			(keepout
				(tracks allowed)
				(vias not_allowed)
				(pads allowed)
				(copperpour not_allowed)
				(footprints allowed)
			)
			(placement
				(enabled no)
				(sheetname "")
			)
			(fill
				(thermal_gap 0.5)
				(thermal_bridge_width 0.5)
				(island_removal_mode 0)
			)
			(polygon
				(pts
					(xy 108.8136 -145.5039) (xy 108.3056 -145.5039) (xy 108.3056 -144.5133) (xy 108.8136 -144.5133)
				)
			)
		)
	)
	(footprint ""
		(layer "B.Cu")
		(at 437.0197 -149.7965)
		(property "Reference" "C25W94"
			(at 0.8382 -0.67818 0)
			(unlocked yes)
			(layer "B.SilkS")
			(effects
				(font
					(size 0.4064 0.254)
					(thickness 0.1524)
				)
				(justify left mirror)
			)
		)
		(property "Value" ""
			(at 0 0 0)
			(layer "B.Fab")
			(effects
				(font
					(size 1.27 1.27)
				)
				(justify mirror)
			)
		)
		(duplicate_pad_numbers_are_jumpers no)
		(fp_poly
			(pts
				(xy -0.3048 -0.1016) (xy -0.3048 0.9906) (xy 0.3048 0.9906) (xy 0.3048 -0.1016)
			)
			(stroke
				(width 0)
				(type default)
			)
			(fill no)
			(layer "B.CrtYd")
		)
		(fp_line
			(start -0.3048 -0.1016)
			(end 0.3048 -0.1016)
			(stroke
				(width 0.1)
				(type default)
			)
			(layer "B.Fab")
		)
		(fp_line
			(start -0.3048 0.9906)
			(end -0.3048 -0.1016)
			(stroke
				(width 0.1)
				(type default)
			)
			(layer "B.Fab")
		)
		(fp_line
			(start 0.3048 -0.1016)
			(end 0.3048 0.9906)
			(stroke
				(width 0.1)
				(type default)
			)
			(layer "B.Fab")
		)
		(fp_line
			(start 0.3048 0.9906)
			(end -0.3048 0.9906)
			(stroke
				(width 0.1)
				(type default)
			)
			(layer "B.Fab")
		)
		(pad "1" smd rect
			(at 0 0 180)
			(size 0.508 0.508)
			(layers "B.Cu" "B.Mask" "B.Paste")
			(net "P3V3_STBY")
		)
		(pad "2" smd rect
			(at 0 0.889 180)
			(size 0.508 0.508)
			(layers "B.Cu" "B.Mask" "B.Paste")
			(net "GND")
		)
		(zone
			(layer "B.Cu")
			(hatch none 0.5)
			(connect_pads
				(clearance 0)
			)
			(min_thickness 0.25)
			(keepout
				(tracks allowed)
				(vias not_allowed)
				(pads allowed)
				(copperpour not_allowed)
				(footprints allowed)
			)
			(placement
				(enabled no)
				(sheetname "")
			)
			(fill
				(thermal_gap 0.5)
				(thermal_bridge_width 0.5)
				(island_removal_mode 0)
			)
			(polygon
				(pts
					(xy 437.2737 -149.5425) (xy 436.7657 -149.5425) (xy 436.7657 -149.1615) (xy 437.2737 -149.1615)
				)
			)
		)
		(zone
			(layer "B.Cu")
			(hatch none 0.5)
			(connect_pads
				(clearance 0)
			)
			(min_thickness 0.25)
			(keepout
				(tracks not_allowed)
				(vias allowed)
				(pads allowed)
				(copperpour not_allowed)
				(footprints allowed)
			)
			(placement
				(enabled no)
				(sheetname "")
			)
			(fill
				(thermal_gap 0.5)
				(thermal_bridge_width 0.5)
				(island_removal_mode 0)
			)
			(polygon
				(pts
					(xy 437.2737 -149.1615) (xy 436.7657 -149.1615) (xy 436.7657 -149.5425) (xy 437.2737 -149.5425)
				)
			)
		)
	)
	(footprint ""
		(layer "B.Cu")
		(at 272.861532 -149.8092 90)
		(property "Reference" "C5G71"
			(at -1.14681 0.76708 180)
			(unlocked yes)
			(layer "B.SilkS")
			(effects
				(font
					(size 0.7874 0.5842)
					(thickness 0.1524)
				)
				(justify mirror)
			)
		)
		(property "Value" ""
			(at 0 0 90)
			(layer "B.Fab")
			(effects
				(font
					(size 1.27 1.27)
				)
				(justify mirror)
			)
		)
		(duplicate_pad_numbers_are_jumpers no)
		(fp_rect
			(start -0.4953 -0.2032)
			(end 0.4953 1.6002)
			(stroke
				(width 0)
				(type default)
			)
			(fill no)
			(layer "B.CrtYd")
		)
		(fp_line
			(start 0.4953 -0.2032)
			(end -0.4953 -0.2032)
			(stroke
				(width 0.1)
				(type default)
			)
			(layer "B.Fab")
		)
		(fp_line
			(start -0.4953 -0.2032)
			(end -0.4953 1.6002)
			(stroke
				(width 0.1)
				(type default)
			)
			(layer "B.Fab")
		)
		(fp_line
			(start 0.4953 1.6002)
			(end 0.4953 -0.2032)
			(stroke
				(width 0.1)
				(type default)
			)
			(layer "B.Fab")
		)
		(fp_line
			(start -0.4953 1.6002)
			(end 0.4953 1.6002)
			(stroke
				(width 0.1)
				(type default)
			)
			(layer "B.Fab")
		)
		(pad "1" smd rect
			(at 0 0 270)
			(size 0.762 0.889)
			(layers "B.Cu" "B.Mask" "B.Paste")
			(net "PVDDQ_DEF")
		)
		(pad "2" smd rect
			(at 0 1.397 270)
			(size 0.762 0.889)
			(layers "B.Cu" "B.Mask" "B.Paste")
			(net "GND")
		)
		(zone
			(layer "B.Cu")
			(hatch none 0.5)
			(connect_pads
				(clearance 0)
			)
			(min_thickness 0.25)
			(keepout
				(tracks not_allowed)
				(vias allowed)
				(pads allowed)
				(copperpour not_allowed)
				(footprints allowed)
			)
			(placement
				(enabled no)
				(sheetname "")
			)
			(fill
				(thermal_gap 0.5)
				(thermal_bridge_width 0.5)
				(island_removal_mode 0)
			)
			(polygon
				(pts
					(xy 273.306032 -149.4282) (xy 273.814032 -149.4282) (xy 273.814032 -150.1902) (xy 273.306032 -150.1902)
				)
			)
		)
	)
)
